# BASEBOARD_FAB2 (Tioga Pass) — schematic netlist excerpt (pin names and nets, part order shuffled) for the footprints in the layout excerpt that follows; sources: Cadence DE-HDL packaged netlist, KiCad conversion of Wiwynn_Tioga_Pass_MB.brd

C7G25  CAP  0.22UF 16V 10% X7R  pkg 0402  page 105 : A = P3E_CPU0_PE2_SS_TXP<5> ; B = P3E_CPU0_PE2_SS_C_TXP<5>
C5D8  CAP_A  22.0UF 4V 20% X6S  pkg 0603V  page 220 : A = PVDDQ_DEF ; B = GND

U1D2  TPS3700  IC  pkg SM  page 200
  OUTB  = IRQ_OC_DETECT_N
  VDD  = P12V_STBY
  INBN  = A_HSC_HIGH
  INAP  = A_HSC_LOW
  GND  = GND
  OUTA  = A_HSC_LOW_GATE

(kicad_pcb
	(version 20260206)
	(generator "pcbnew")
	(generator_version "10.0")
	(general
		(thickness 1.6)
		(legacy_teardrops no)
	)
	(paper "A4")
	(title_block
		(title "Wiwynn_Tioga_Pass_MB.brd")
		(comment 1 "Tioga Pass / footprints 379-381 of 4770")
	)
	(layers
		(0 "F.Cu" signal "TOP")
		(4 "In1.Cu" signal "L2GND")
		(6 "In2.Cu" signal "L3")
		(8 "In3.Cu" signal "L4GND")
		(10 "In4.Cu" signal "L5")
		(12 "In5.Cu" signal "L6GND")
		(14 "In6.Cu" signal "L7VCC")
		(16 "In7.Cu" signal "L8VCC")
		(18 "In8.Cu" signal "L9GND")
		(20 "In9.Cu" signal "L10")
		(22 "In10.Cu" signal "L11GND")
		(24 "In11.Cu" signal "L12")
		(26 "In12.Cu" signal "L13GND")
		(2 "B.Cu" signal "BOTTOM")
		(9 "F.Adhes" user "F.Adhesive")
		(11 "B.Adhes" user "B.Adhesive")
		(13 "F.Paste" user "Package Geometry/Pastemask Top")
		(15 "B.Paste" user "Package Geometry/Pastemask Bottom")
		(5 "F.SilkS" user "Ref Des/Silkscreen Top")
		(7 "B.SilkS" user "Ref Des/Silkscreen Bottom")
		(1 "F.Mask" user "Board Geometry/Soldermask Top")
		(3 "B.Mask" user "Board Geometry/Soldermask Bottom")
		(17 "Dwgs.User" user "User.Drawings")
		(19 "Cmts.User" user "User.Comments")
		(21 "Eco1.User" user "User.Eco1")
		(23 "Eco2.User" user "User.Eco2")
		(25 "Edge.Cuts" user "Board Geometry/Outline")
		(27 "Margin" user)
		(31 "F.CrtYd" user "Package Geometry/Place Bound Top")
		(29 "B.CrtYd" user "Package Geometry/Place Bound Bottom")
		(35 "F.Fab" user "Ref Des/Assembly Top")
		(33 "B.Fab" user "Ref Des/Assembly Bottom")
	)
	(footprint ""
		(layer "F.Cu")
		(at 267.2588 -84.7598)
		(property "Reference" "C5D8"
			(at 0 0 0)
			(layer "F.SilkS")
			(hide yes)
			(effects
				(font
					(size 1.27 1.27)
				)
			)
		)
		(property "Value" ""
			(at 0 0 0)
			(layer "F.Fab")
			(effects
				(font
					(size 1.27 1.27)
				)
			)
		)
		(duplicate_pad_numbers_are_jumpers no)
		(fp_poly
			(pts
				(xy -0.4953 -0.2032) (xy 0.4953 -0.2032) (xy 0.4953 1.6002) (xy -0.4953 1.6002)
			)
			(stroke
				(width 0)
				(type default)
			)
			(fill no)
			(layer "F.CrtYd")
		)
		(fp_line
			(start -0.4953 -0.2032)
			(end 0.4953 -0.2032)
			(stroke
				(width 0.1)
				(type default)
			)
			(layer "F.Fab")
		)
		(fp_line
			(start -0.4953 1.6002)
			(end -0.4953 -0.2032)
			(stroke
				(width 0.1)
				(type default)
			)
			(layer "F.Fab")
		)
		(fp_line
			(start 0.4953 -0.2032)
			(end 0.4953 1.6002)
			(stroke
				(width 0.1)
				(type default)
			)
			(layer "F.Fab")
		)
		(fp_line
			(start 0.4953 1.6002)
			(end -0.4953 1.6002)
			(stroke
				(width 0.1)
				(type default)
			)
			(layer "F.Fab")
		)
		(pad "1" smd rect
			(at 0 0)
			(size 0.762 0.889)
			(layers "F.Cu" "F.Mask" "F.Paste")
			(net "PVDDQ_DEF")
		)
		(pad "2" smd rect
			(at 0 1.397)
			(size 0.762 0.889)
			(layers "F.Cu" "F.Mask" "F.Paste")
			(net "GND")
		)
		(zone
			(layer "F.Cu")
			(hatch none 0.5)
			(connect_pads
				(clearance 0)
			)
			(min_thickness 0.25)
			(keepout
				(tracks not_allowed)
				(vias allowed)
				(pads allowed)
				(copperpour not_allowed)
				(footprints allowed)
			)
			(placement
				(enabled no)
				(sheetname "")
			)
			(fill
				(thermal_gap 0.5)
				(thermal_bridge_width 0.5)
				(island_removal_mode 0)
			)
			(polygon
				(pts
					(xy 266.8778 -84.3153) (xy 267.6398 -84.3153) (xy 267.6398 -83.8073) (xy 266.8778 -83.8073)
				)
			)
		)
	)
	(footprint ""
		(layer "F.Cu")
		(at 20.9423 -83.312 90)
		(property "Reference" "U1D2"
			(at 1.1684 -0.90043 90)
			(unlocked yes)
			(layer "F.SilkS")
			(effects
				(font
					(size 0.7874 0.5842)
					(thickness 0.1524)
				)
			)
		)
		(property "Value" ""
			(at 0 0 90)
			(layer "F.Fab")
			(effects
				(font
					(size 1.27 1.27)
				)
			)
		)
		(duplicate_pad_numbers_are_jumpers no)
		(fp_circle
			(center -1.0795 -0.054102)
			(end -1.0795 0.072898)
			(stroke
				(width 0.254)
				(type default)
			)
			(fill no)
			(layer "F.SilkS")
		)
		(fp_rect
			(start -0.216154 1.27508)
			(end 1.333754 -0.275082)
			(stroke
				(width 0)
				(type default)
			)
			(fill no)
			(layer "F.CrtYd")
		)
		(fp_line
			(start 1.333754 -0.275082)
			(end 1.333754 1.27508)
			(stroke
				(width 0.1)
				(type default)
			)
			(layer "F.Fab")
		)
		(fp_line
			(start -0.216154 -0.275082)
			(end 1.333754 -0.275082)
			(stroke
				(width 0.1)
				(type default)
			)
			(layer "F.Fab")
		)
		(fp_line
			(start 1.333754 1.27508)
			(end -0.216154 1.27508)
			(stroke
				(width 0.1)
				(type default)
			)
			(layer "F.Fab")
		)
		(fp_line
			(start -0.216154 1.27508)
			(end -0.216154 -0.275082)
			(stroke
				(width 0.1)
				(type default)
			)
			(layer "F.Fab")
		)
		(fp_circle
			(center -1.0795 -0.054102)
			(end -1.0795 0.072898)
			(stroke
				(width 0.635)
				(type default)
			)
			(fill no)
			(layer "F.Fab")
		)
		(pad "1" smd rect
			(at 0 0 90)
			(size 0.9398 0.3048)
			(layers "F.Cu" "F.Mask" "F.Paste")
			(net "IRQ_OC_DETECT_N")
		)
		(pad "2" smd rect
			(at -0.0254 0.500126 90)
			(size 0.889 0.3048)
			(layers "F.Cu" "F.Mask" "F.Paste")
			(net "P12V_STBY")
		)
		(pad "3" smd rect
			(at -0.0254 0.999998 90)
			(size 0.889 0.3048)
			(layers "F.Cu" "F.Mask" "F.Paste")
			(net "A_HSC_HIGH")
		)
		(pad "4" smd rect
			(at 1.143 0.999998 90)
			(size 0.889 0.3048)
			(layers "F.Cu" "F.Mask" "F.Paste")
			(net "A_HSC_LOW")
		)
		(pad "5" smd rect
			(at 1.143 0.500126 90)
			(size 0.889 0.3048)
			(layers "F.Cu" "F.Mask" "F.Paste")
			(net "GND")
		)
		(pad "6" smd rect
			(at 1.143 0 90)
			(size 0.889 0.3048)
			(layers "F.Cu" "F.Mask" "F.Paste")
			(net "A_HSC_LOW_GATE")
		)
	)
	(footprint ""
		(layer "F.Cu")
		(at 398.030192 -10.917936)
		(property "Reference" "C7G25"
			(at 0 0 0)
			(layer "F.SilkS")
			(hide yes)
			(effects
				(font
					(size 1.27 1.27)
				)
			)
		)
		(property "Value" ""
			(at 0 0 0)
			(layer "F.Fab")
			(effects
				(font
					(size 1.27 1.27)
				)
			)
		)
		(duplicate_pad_numbers_are_jumpers no)
		(fp_rect
			(start -0.3048 0.9906)
			(end 0.3048 -0.1016)
			(stroke
				(width 0)
				(type default)
			)
			(fill no)
			(layer "F.CrtYd")
		)
		(fp_line
			(start -0.3048 -0.1016)
			(end -0.3048 0.9906)
			(stroke
				(width 0.1)
				(type default)
			)
			(layer "F.Fab")
		)
		(fp_line
			(start -0.3048 0.9906)
			(end 0.3048 0.9906)
			(stroke
				(width 0.1)
				(type default)
			)
			(layer "F.Fab")
		)
		(fp_line
			(start 0.3048 -0.1016)
			(end -0.3048 -0.1016)
			(stroke
				(width 0.1)
				(type default)
			)
			(layer "F.Fab")
		)
		(fp_line
			(start 0.3048 0.9906)
			(end 0.3048 -0.1016)
			(stroke
				(width 0.1)
				(type default)
			)
			(layer "F.Fab")
		)
		(pad "1" smd rect
			(at 0 0)
			(size 0.508 0.508)
			(layers "F.Cu" "F.Mask" "F.Paste")
			(net "P3E_CPU0_PE2_SS_TXP<5>")
		)
		(pad "2" smd rect
			(at 0 0.889)
			(size 0.508 0.508)
			(layers "F.Cu" "F.Mask" "F.Paste")
			(net "P3E_CPU0_PE2_SS_C_TXP<5>")
		)
		(zone
			(layer "F.Cu")
			(hatch none 0.5)
			(connect_pads
				(clearance 0)
			)
			(min_thickness 0.25)
			(keepout
				(tracks not_allowed)
				(vias allowed)
				(pads allowed)
				(copperpour not_allowed)
				(footprints allowed)
			)
			(placement
				(enabled no)
				(sheetname "")
			)
			(fill
				(thermal_gap 0.5)
				(thermal_bridge_width 0.5)
				(island_removal_mode 0)
			)
			(polygon
				(pts
					(xy 397.776192 -10.282936) (xy 398.284192 -10.282936) (xy 398.284192 -10.663936) (xy 397.776192 -10.663936)
				)
			)
		)
		(zone
			(layer "F.Cu")
			(hatch none 0.5)
			(connect_pads
				(clearance 0)
			)
			(min_thickness 0.25)
			(keepout
				(tracks allowed)
				(vias not_allowed)
				(pads allowed)
				(copperpour not_allowed)
				(footprints allowed)
			)
			(placement
				(enabled no)
				(sheetname "")
			)
			(fill
				(thermal_gap 0.5)
				(thermal_bridge_width 0.5)
				(island_removal_mode 0)
			)
			(polygon
				(pts
					(xy 397.776192 -10.282936) (xy 398.284192 -10.282936) (xy 398.284192 -10.663936) (xy 397.776192 -10.663936)
				)
			)
		)
	)
)
